FILE_TYPE = CONNECTIVITY;
{Allegro Design Entry HDL 16.6-p007 (v16-6-112F) 10/10/2012}
"PAGE_NUMBER" = 74;
0"NC";
1"GND\g";
2"GND\g";
3"GND\g";
4"GND\g";
5"GND\g";
6"GND\g";
7"GND\g";
8"GND\g";
%"GND"
"1","(-7625,475)","0","mstr_symbols","I1";
;
HDL_POWER"GND"
BODY_TYPE"PLUMBING"
CDS_LIB"mstr_symbols"
SIZE"1B"
VOLTAGE"0.0V";
"A\NAC"1;
%"GND"
"1","(-2425,500)","0","mstr_symbols","I11";
;
HDL_POWER"GND"
BODY_TYPE"PLUMBING"
SIZE"1B"
CDS_LIB"mstr_symbols"
VOLTAGE"0.0V";
"A\NAC"2;
%"GND"
"1","(-2025,475)","0","mstr_symbols","I12";
;
HDL_POWER"GND"
BODY_TYPE"PLUMBING"
CDS_LIB"mstr_symbols"
SIZE"1B"
VOLTAGE"0.0V";
"A\NAC"3;
%"GND"
"1","(-500,475)","0","mstr_symbols","I14";
;
HDL_POWER"GND"
BODY_TYPE"PLUMBING"
CDS_LIB"mstr_symbols"
SIZE"1B"
VOLTAGE"0.0V";
"A\NAC"4;
%"SKX_EXT_B"
"23","(-6875,2600)","0","chpset_lib","I20";
;
CDS_SEC"23"
CDS_LOCATION"U2D1"
SEC"23"
CDS_LIB"chpset_lib"
SEC_TYPE"BGA1"
PACK_TYPE"BGA1"
MATERIAL"IC"
PART_NUMBER"TBD"
LOCATION"U2D1";
"VSS<1094>"
$PN"J74"5;
"VSS<1095>"
$PN"J72"5;
"VSS<1096>"
$PN"J40"5;
"VSS<1097>"
$PN"J38"5;
"VSS<1098>"
$PN"J34"5;
"VSS<1099>"
$PN"J32"5;
"VSS<1100>"
$PN"J28"5;
"VSS<1101>"
$PN"J26"5;
"VSS<1102>"
$PN"J22"5;
"VSS<1103>"
$PN"J14"5;
"VSS<1104>"
$PN"J12"5;
"VSS<1105>"
$PN"J4"5;
"VSS<1106>"
$PN"DN44"5;
"VSS<1107>"
$PN"H75"5;
"VSS<1108>"
$PN"H71"5;
"VSS<1109>"
$PN"H65"5;
"VSS<1110>"
$PN"H41"5;
"VSS<1111>"
$PN"H39"5;
"VSS<1112>"
$PN"H37"5;
"VSS<1113>"
$PN"H35"5;
"VSS<1114>"
$PN"H33"5;
"VSS<1115>"
$PN"H31"5;
"VSS<1116>"
$PN"H29"5;
"VSS<1117>"
$PN"H27"5;
"VSS<1118>"
$PN"H25"5;
"VSS<1119>"
$PN"H11"5;
"VSS<1120>"
$PN"H3"5;
"VSS<1121>"
$PN"G82"5;
"VSS<1122>"
$PN"G80"5;
"VSS<1123>"
$PN"G78"5;
"VSS<1124>"
$PN"G76"5;
"VSS<1125>"
$PN"G70"5;
"VSS<1126>"
$PN"G66"5;
"VSS<1127>"
$PN"G42"5;
"VSS<1128>"
$PN"G38"5;
"VSS<1129>"
$PN"G36"5;
"VSS<1130>"
$PN"G32"5;
"VSS<1131>"
$PN"G30"5;
"VSS<1132>"
$PN"G26"5;
"VSS<1133>"
$PN"G24"5;
"VSS<1134>"
$PN"G22"5;
"VSS<1135>"
$PN"G8"5;
"VSS<1136>"
$PN"G4"5;
"VSS<1137>"
$PN"F69"5;
"VSS<1138>"
$PN"F67"5;
"VSS<1139>"
$PN"F43"5;
"VSS<1140>"
$PN"F37"5;
"VSS<1141>"
$PN"F31"5;
"VSS<1142>"
$PN"F25"5;
"VSS<1143>"
$PN"F19"5;
"VSS<1144>"
$PN"F17"5;
"VSS<1145>"
$PN"F5"5;
"VSS<1146>"
$PN"E76"5;
"VSS<1147>"
$PN"E74"5;
"VSS<1148>"
$PN"E72"5;
"VSS<1149>"
$PN"E22"5;
"VSS<1150>"
$PN"E20"5;
"VSS<1151>"
$PN"E18"5;
"VSS<1152>"
$PN"E16"5;
"VSS<1153>"
$PN"E8"5;
"VSS<1154>"
$PN"E6"5;
"VSS<1155>"
$PN"D77"5;
"VSS<1156>"
$PN"D43"5;
"VSS<1157>"
$PN"D41"5;
"VSS<1158>"
$PN"D39"5;
"VSS<1159>"
$PN"D37"5;
"VSS<1160>"
$PN"D35"5;
"VSS<1161>"
$PN"D33"5;
"VSS<1162>"
$PN"D31"5;
"VSS<1163>"
$PN"D29"5;
"VSS<1164>"
$PN"D27"5;
"VSS<1165>"
$PN"D25"5;
"VSS<1166>"
$PN"D13"5;
"VSS<1167>"
$PN"D11"5;
"VSS<1168>"
$PN"CM27"5;
"VSS<1169>"
$PN"C78"5;
"VSS<1170>"
$PN"C76"5;
"VSS<1171>"
$PN"C16"5;
"VSS<1172>"
$PN"C14"5;
"VSS<1173>"
$PN"C12"5;
"VSS<1174>"
$PN"C10"1;
"VSS<1175>"
$PN"C8"1;
"VSS<1176>"
$PN"B75"1;
"VSS<1177>"
$PN"B71"1;
"VSS<1178>"
$PN"B37"1;
"VSS<1179>"
$PN"B31"1;
"VSS<1180>"
$PN"B25"1;
"VSS<1181>"
$PN"A38"1;
"VSS<1182>"
$PN"A36"1;
"VSS<1183>"
$PN"A32"1;
"VSS<1184>"
$PN"A30"1;
"VSS<1185>"
$PN"A26"1;
"VSS<1186>"
$PN"AC58"1;
"VSS<1187>"
$PN"AC60"1;
"VSS<1188>"
$PN"AC62"1;
"VSS<1189>"
$PN"AJ4"1;
"VSS<1190>"
$PN"AR6"1;
"VSS<1191>"
$PN"CG6"1;
"VSS<1192>"
$PN"CW6"1;
"VSS<1193>"
$PN"DE48"1;
"VSS<1194>"
$PN"DE50"1;
"VSS<1195>"
$PN"DE52"1;
"VSS<1196>"
$PN"DE54"1;
"VSS<1197>"
$PN"DE56"1;
"VSS<1198>"
$PN"DE58"1;
"VSS<1199>"
$PN"DE60"1;
"VSS<1200>"
$PN"DE62"1;
"VSS<1201>"
$PN"DL8"1;
"VSS<1202>"
$PN"DN18"1;
"VSS<1203>"
$PN"DP45"1;
"VSS<1204>"
$PN"DP47"1;
"VSS<1205>"
$PN"DP49"1;
"VSS<1206>"
$PN"DP51"1;
"VSS<1207>"
$PN"DP53"1;
"VSS<1208>"
$PN"DP55"1;
"VSS<1209>"
$PN"DP57"1;
"VSS<1210>"
$PN"DP59"1;
"VSS<1211>"
$PN"DP61"1;
"VSS<1212>"
$PN"DP63"1;
"VSS<1213>"
$PN"DP9"1;
"VSS<1214>"
$PN"DV19"1;
"VSS<1215>"
$PN"DY45"1;
"VSS<1216>"
$PN"DY47"1;
"VSS<1217>"
$PN"DY49"1;
"VSS<1218>"
$PN"DY51"1;
"VSS<1219>"
$PN"DY53"1;
"VSS<1220>"
$PN"DY55"1;
"VSS<1221>"
$PN"DY57"1;
"VSS<1222>"
$PN"DY59"1;
"VSS<1223>"
$PN"DY61"1;
"VSS<1224>"
$PN"DY63"1;
"VSS<1225>"
$PN"EA14"1;
"VSS<1226>"
$PN"L8"1;
"VSS<1227>"
$PN"V11"1;
"VSS<1228>"
$PN"E66"1;
"VSS<1229>"
$PN"ED69"1;
"VSS<1230>"
$PN"EE80"1;
"VSS<1231>"
$PN"EE8"1;
"VSS<1232>"
$PN"EE40"1;
"VSS<1233>"
$PN"ED81"1;
"VSS<1234>"
$PN"ED7"1;
"VSS<1235>"
$PN"ED41"1;
"VSS<1236>"
$PN"EC82"1;
"VSS<1237>"
$PN"EC6"1;
"VSS<1238>"
$PN"EC42"1;
"VSS<1239>"
$PN"DW2"1;
"VSS<1240>"
$PN"EB83"1;
"VSS<1241>"
$PN"EA84"1;
"VSS<1242>"
$PN"DY85"1;
"VSS<1243>"
$PN"J86"1;
"VSS<1244>"
$PN"E82"1;
"VSS<1245>"
$PN"D81"1;
"VSS<1246>"
$PN"D3"1;
"VSS<1247>"
$PN"C80"1;
"VSS<1248>"
$PN"C4"1;
"VSS<1249>"
$PN"B79"1;
"VSS<1250>"
$PN"B5"1;
"VSS<1251>"
$PN"B43"1;
"VSS<1252>"
$PN"A42"1;
"VSS<1253>"
$PN"B9"1;
%"SKX_EXT_B"
"24","(-5025,2625)","0","chpset_lib","I21";
;
CDS_SEC"24"
CDS_LOCATION"U2D1"
SEC"24"
CDS_LIB"chpset_lib"
SEC_TYPE"BGA1"
PACK_TYPE"BGA1"
MATERIAL"IC"
PART_NUMBER"TBD"
LOCATION"U2D1";
"VSS<934>"
$PN"AA16"7;
"VSS<935>"
$PN"AA4"7;
"VSS<936>"
$PN"Y85"7;
"VSS<937>"
$PN"Y83"7;
"VSS<938>"
$PN"Y81"7;
"VSS<939>"
$PN"Y79"7;
"VSS<940>"
$PN"Y73"7;
"VSS<941>"
$PN"Y71"7;
"VSS<942>"
$PN"Y9"7;
"VSS<943>"
$PN"Y7"7;
"VSS<944>"
$PN"Y67"7;
"VSS<945>"
$PN"Y5"7;
"VSS<946>"
$PN"Y17"7;
"VSS<947>"
$PN"Y15"7;
"VSS<948>"
$PN"W82"7;
"VSS<949>"
$PN"W78"7;
"VSS<950>"
$PN"W74"7;
"VSS<951>"
$PN"W68"7;
"VSS<952>"
$PN"W42"7;
"VSS<953>"
$PN"W40"7;
"VSS<954>"
$PN"W38"7;
"VSS<955>"
$PN"W36"7;
"VSS<956>"
$PN"W34"7;
"VSS<957>"
$PN"W32"7;
"VSS<958>"
$PN"W30"7;
"VSS<959>"
$PN"W28"7;
"VSS<960>"
$PN"W26"7;
"VSS<961>"
$PN"W24"7;
"VSS<962>"
$PN"W22"7;
"VSS<963>"
$PN"W12"7;
"VSS<964>"
$PN"AC56"7;
"VSS<965>"
$PN"W8"7;
"VSS<966>"
$PN"V83"7;
"VSS<967>"
$PN"V77"7;
"VSS<968>"
$PN"V75"7;
"VSS<969>"
$PN"V73"7;
"VSS<970>"
$PN"V43"7;
"VSS<971>"
$PN"V23"7;
"VSS<972>"
$PN"V21"7;
"VSS<973>"
$PN"V15"7;
"VSS<974>"
$PN"V13"7;
"VSS<975>"
$PN"V9"7;
"VSS<976>"
$PN"V5"7;
"VSS<977>"
$PN"V1"7;
"VSS<978>"
$PN"U86"7;
"VSS<979>"
$PN"U80"7;
"VSS<980>"
$PN"U78"7;
"VSS<981>"
$PN"U76"7;
"VSS<982>"
$PN"U74"7;
"VSS<983>"
$PN"U70"7;
"VSS<984>"
$PN"U68"7;
"VSS<985>"
$PN"U42"7;
"VSS<986>"
$PN"U36"7;
"VSS<987>"
$PN"U30"7;
"VSS<988>"
$PN"U24"7;
"VSS<989>"
$PN"U22"7;
"VSS<990>"
$PN"U20"7;
"VSS<991>"
$PN"U6"7;
"VSS<992>"
$PN"U4"7;
"VSS<993>"
$PN"U2"7;
"VSS<994>"
$PN"T85"7;
"VSS<995>"
$PN"T83"7;
"VSS<996>"
$PN"T77"7;
"VSS<997>"
$PN"T73"7;
"VSS<998>"
$PN"T65"7;
"VSS<999>"
$PN"T41"7;
"VSS<1000>"
$PN"T37"7;
"VSS<1001>"
$PN"T35"7;
"VSS<1002>"
$PN"T31"7;
"VSS<1003>"
$PN"T29"7;
"VSS<1004>"
$PN"T25"7;
"VSS<1005>"
$PN"T17"7;
"VSS<1006>"
$PN"T13"7;
"VSS<1007>"
$PN"R86"7;
"VSS<1008>"
$PN"R78"7;
"VSS<1009>"
$PN"R72"7;
"VSS<1010>"
$PN"R68"7;
"VSS<1011>"
$PN"R40"7;
"VSS<1012>"
$PN"R38"7;
"VSS<1013>"
$PN"R34"7;
"VSS<1014>"
$PN"R32"6;
"VSS<1015>"
$PN"R28"6;
"VSS<1016>"
$PN"R26"6;
"VSS<1017>"
$PN"R22"6;
"VSS<1018>"
$PN"R4"6;
"VSS<1019>"
$PN"R2"6;
"VSS<1020>"
$PN"R18"6;
"VSS<1021>"
$PN"R14"6;
"VSS<1022>"
$PN"P83"6;
"VSS<1023>"
$PN"P81"6;
"VSS<1024>"
$PN"P71"6;
"VSS<1025>"
$PN"P69"6;
"VSS<1026>"
$PN"P67"6;
"VSS<1027>"
$PN"P39"6;
"VSS<1028>"
$PN"P33"6;
"VSS<1029>"
$PN"P27"6;
"VSS<1030>"
$PN"P15"6;
"VSS<1031>"
$PN"P11"6;
"VSS<1032>"
$PN"N8"6;
"VSS<1033>"
$PN"N4"6;
"VSS<1034>"
$PN"N78"6;
"VSS<1035>"
$PN"N76"6;
"VSS<1036>"
$PN"N74"6;
"VSS<1037>"
$PN"N72"6;
"VSS<1038>"
$PN"N70"6;
"VSS<1039>"
$PN"N66"6;
"VSS<1040>"
$PN"N6"6;
"VSS<1041>"
$PN"N22"6;
"VSS<1042>"
$PN"N20"6;
"VSS<1043>"
$PN"DM19"6;
"VSS<1044>"
$PN"M85"6;
"VSS<1045>"
$PN"M83"6;
"VSS<1046>"
$PN"M79"6;
"VSS<1047>"
$PN"M71"6;
"VSS<1048>"
$PN"M65"6;
"VSS<1049>"
$PN"M43"6;
"VSS<1050>"
$PN"M41"6;
"VSS<1051>"
$PN"M39"6;
"VSS<1052>"
$PN"M37"6;
"VSS<1053>"
$PN"M35"6;
"VSS<1054>"
$PN"M33"6;
"VSS<1055>"
$PN"M31"6;
"VSS<1056>"
$PN"M29"6;
"VSS<1057>"
$PN"M27"6;
"VSS<1058>"
$PN"M25"6;
"VSS<1059>"
$PN"M23"6;
"VSS<1060>"
$PN"M19"6;
"VSS<1061>"
$PN"M17"6;
"VSS<1062>"
$PN"M15"6;
"VSS<1063>"
$PN"CT7"6;
"VSS<1064>"
$PN"BT9"6;
"VSS<1065>"
$PN"L82"6;
"VSS<1066>"
$PN"L80"6;
"VSS<1067>"
$PN"L78"6;
"VSS<1068>"
$PN"L72"6;
"VSS<1069>"
$PN"L22"6;
"VSS<1070>"
$PN"L20"6;
"VSS<1071>"
$PN"L6"6;
"VSS<1072>"
$PN"L2"6;
"VSS<1073>"
$PN"L10"6;
"VSS<1074>"
$PN"K85"6;
"VSS<1075>"
$PN"K83"6;
"VSS<1076>"
$PN"K81"6;
"VSS<1077>"
$PN"K77"6;
"VSS<1078>"
$PN"K73"6;
"VSS<1079>"
$PN"K71"6;
"VSS<1080>"
$PN"K69"6;
"VSS<1081>"
$PN"K67"6;
"VSS<1082>"
$PN"K65"6;
"VSS<1083>"
$PN"K39"6;
"VSS<1084>"
$PN"K33"6;
"VSS<1085>"
$PN"K27"6;
"VSS<1086>"
$PN"DB7"6;
"VSS<1087>"
$PN"K17"6;
"VSS<1088>"
$PN"K13"6;
"VSS<1089>"
$PN"K11"6;
"VSS<1090>"
$PN"K1"6;
"VSS<1091>"
$PN"J84"6;
"VSS<1092>"
$PN"J82"6;
"VSS<1093>"
$PN"J76"6;
%"SKX_EXT_B"
"25","(-3200,2625)","0","chpset_lib","I22";
;
CDS_SEC"25"
CDS_LOCATION"U2D1"
SEC"25"
CDS_LIB"chpset_lib"
SEC_TYPE"BGA1"
PACK_TYPE"BGA1"
MATERIAL"IC"
PART_NUMBER"TBD"
LOCATION"U2D1";
"VSS<774>"
$PN"AL68"2;
"VSS<775>"
$PN"AL64"2;
"VSS<776>"
$PN"AL56"2;
"VSS<777>"
$PN"AL32"2;
"VSS<778>"
$PN"AL30"2;
"VSS<779>"
$PN"AL24"2;
"VSS<780>"
$PN"AL10"2;
"VSS<781>"
$PN"AL4"2;
"VSS<782>"
$PN"AK85"2;
"VSS<783>"
$PN"AK83"2;
"VSS<784>"
$PN"AK81"2;
"VSS<785>"
$PN"AK79"2;
"VSS<786>"
$PN"AK73"2;
"VSS<787>"
$PN"AK67"2;
"VSS<788>"
$PN"AK65"2;
"VSS<789>"
$PN"AK55"2;
"VSS<790>"
$PN"AK33"2;
"VSS<791>"
$PN"AK31"2;
"VSS<792>"
$PN"AK29"2;
"VSS<793>"
$PN"AK25"2;
"VSS<794>"
$PN"AK23"2;
"VSS<795>"
$PN"AK19"2;
"VSS<796>"
$PN"AK13"2;
"VSS<797>"
$PN"AK9"2;
"VSS<798>"
$PN"AJ86"2;
"VSS<799>"
$PN"AJ82"2;
"VSS<800>"
$PN"AJ78"2;
"VSS<801>"
$PN"AJ74"2;
"VSS<802>"
$PN"AJ68"2;
"VSS<803>"
$PN"AJ66"2;
"VSS<804>"
$PN"AJ54"2;
"VSS<805>"
$PN"AJ52"2;
"VSS<806>"
$PN"AJ50"2;
"VSS<807>"
$PN"AJ48"2;
"VSS<808>"
$PN"AJ46"2;
"VSS<809>"
$PN"AJ34"2;
"VSS<810>"
$PN"AJ32"2;
"VSS<811>"
$PN"AJ28"2;
"VSS<812>"
$PN"AJ26"2;
"VSS<813>"
$PN"AJ22"2;
"VSS<814>"
$PN"AJ8"2;
"VSS<815>"
$PN"AH83"2;
"VSS<816>"
$PN"AH77"2;
"VSS<817>"
$PN"AH75"2;
"VSS<818>"
$PN"AH69"2;
"VSS<819>"
$PN"AH65"2;
"VSS<820>"
$PN"AH61"2;
"VSS<821>"
$PN"AH59"2;
"VSS<822>"
$PN"AH53"2;
"VSS<823>"
$PN"AH51"2;
"VSS<824>"
$PN"AH49"2;
"VSS<825>"
$PN"AH47"2;
"VSS<826>"
$PN"AH45"2;
"VSS<827>"
$PN"AH35"2;
"VSS<828>"
$PN"AH33"2;
"VSS<829>"
$PN"AH27"2;
"VSS<830>"
$PN"AH21"2;
"VSS<831>"
$PN"AH5"2;
"VSS<832>"
$PN"AH1"2;
"VSS<833>"
$PN"AG80"2;
"VSS<834>"
$PN"AG78"2;
"VSS<835>"
$PN"AG76"2;
"VSS<836>"
$PN"AG74"2;
"VSS<837>"
$PN"AG70"2;
"VSS<838>"
$PN"AG64"2;
"VSS<839>"
$PN"AG36"2;
"VSS<840>"
$PN"AG18"2;
"VSS<841>"
$PN"AG14"2;
"VSS<842>"
$PN"AG12"2;
"VSS<843>"
$PN"AF85"2;
"VSS<844>"
$PN"AF83"2;
"VSS<845>"
$PN"AF77"2;
"VSS<846>"
$PN"AF73"2;
"VSS<847>"
$PN"AF41"2;
"VSS<848>"
$PN"AF39"2;
"VSS<849>"
$PN"AF37"2;
"VSS<850>"
$PN"AF33"2;
"VSS<851>"
$PN"AF31"2;
"VSS<852>"
$PN"AF29"2;
"VSS<853>"
$PN"AF27"2;
"VSS<854>"
$PN"AF25"8;
"VSS<855>"
$PN"AF23"8;
"VSS<856>"
$PN"AF21"8;
"VSS<857>"
$PN"AF9"8;
"VSS<858>"
$PN"AC52"8;
"VSS<859>"
$PN"AF1"8;
"VSS<860>"
$PN"AE78"8;
"VSS<861>"
$PN"AE70"8;
"VSS<862>"
$PN"AE68"8;
"VSS<863>"
$PN"AE66"8;
"VSS<864>"
$PN"AE64"8;
"VSS<865>"
$PN"AE42"8;
"VSS<866>"
$PN"AE40"8;
"VSS<867>"
$PN"AE38"8;
"VSS<868>"
$PN"AE16"8;
"VSS<869>"
$PN"AC54"8;
"VSS<870>"
$PN"AE8"8;
"VSS<871>"
$PN"AE4"8;
"VSS<872>"
$PN"AD85"8;
"VSS<873>"
$PN"AD83"8;
"VSS<874>"
$PN"AD81"8;
"VSS<875>"
$PN"AD75"8;
"VSS<876>"
$PN"AD73"8;
"VSS<877>"
$PN"AD71"8;
"VSS<878>"
$PN"AD43"8;
"VSS<879>"
$PN"AD39"8;
"VSS<880>"
$PN"AD33"8;
"VSS<881>"
$PN"AD27"8;
"VSS<882>"
$PN"AD21"8;
"VSS<883>"
$PN"AD19"8;
"VSS<884>"
$PN"AD15"8;
"VSS<885>"
$PN"AD13"8;
"VSS<886>"
$PN"AD11"8;
"VSS<887>"
$PN"AD9"8;
"VSS<888>"
$PN"AD7"8;
"VSS<889>"
$PN"AD3"8;
"VSS<890>"
$PN"AC86"8;
"VSS<891>"
$PN"AC84"8;
"VSS<892>"
$PN"AC78"8;
"VSS<893>"
$PN"AC72"8;
"VSS<894>"
$PN"AC70"8;
"VSS<895>"
$PN"AC64"8;
"VSS<896>"
$PN"AC40"8;
"VSS<897>"
$PN"AC38"8;
"VSS<898>"
$PN"AC34"8;
"VSS<899>"
$PN"AC32"8;
"VSS<900>"
$PN"AC28"8;
"VSS<901>"
$PN"AC26"8;
"VSS<902>"
$PN"AC22"8;
"VSS<903>"
$PN"AC18"8;
"VSS<904>"
$PN"AB85"8;
"VSS<905>"
$PN"AB83"8;
"VSS<906>"
$PN"AB79"8;
"VSS<907>"
$PN"AB73"8;
"VSS<908>"
$PN"AB69"8;
"VSS<909>"
$PN"AB65"8;
"VSS<910>"
$PN"AB41"8;
"VSS<911>"
$PN"AB37"8;
"VSS<912>"
$PN"AB35"8;
"VSS<913>"
$PN"AB31"8;
"VSS<914>"
$PN"AB29"8;
"VSS<915>"
$PN"AB25"8;
"VSS<916>"
$PN"AB23"8;
"VSS<917>"
$PN"AB21"8;
"VSS<918>"
$PN"AB11"8;
"VSS<919>"
$PN"AB5"8;
"VSS<920>"
$PN"AB1"8;
"VSS<921>"
$PN"AA82"8;
"VSS<922>"
$PN"AA80"8;
"VSS<923>"
$PN"AA78"8;
"VSS<924>"
$PN"AA76"8;
"VSS<925>"
$PN"AA68"8;
"VSS<926>"
$PN"AA66"8;
"VSS<927>"
$PN"AA64"8;
"VSS<928>"
$PN"AA42"8;
"VSS<929>"
$PN"AA36"8;
"VSS<930>"
$PN"AA30"8;
"VSS<931>"
$PN"AA24"8;
"VSS<932>"
$PN"AA22"8;
"VSS<933>"
$PN"AA18"8;
%"SKX_EXT_B"
"26","(-1275,2600)","0","chpset_lib","I23";
;
CDS_SEC"26"
CDS_LOCATION"U2D1"
SEC"26"
CDS_LIB"chpset_lib"
SEC_TYPE"BGA1"
PACK_TYPE"BGA1"
MATERIAL"IC"
PART_NUMBER"TBD"
LOCATION"U2D1";
"VSS<614>"
$PN"BG72"4;
"VSS<615>"
$PN"BG24"4;
"VSS<616>"
$PN"BG22"4;
"VSS<617>"
$PN"BG10"4;
"VSS<618>"
$PN"BG8"4;
"VSS<619>"
$PN"BG6"4;
"VSS<620>"
$PN"BF71"4;
"VSS<621>"
$PN"BF69"4;
"VSS<622>"
$PN"BF67"4;
"VSS<623>"
$PN"BF65"4;
"VSS<624>"
$PN"BF63"4;
"VSS<625>"
$PN"BF25"4;
"VSS<626>"
$PN"BF19"4;
"VSS<627>"
$PN"BF17"4;
"VSS<628>"
$PN"BF15"4;
"VSS<629>"
$PN"BF9"4;
"VSS<630>"
$PN"BE70"4;
"VSS<631>"
$PN"BE68"4;
"VSS<632>"
$PN"BE66"4;
"VSS<633>"
$PN"BE64"4;
"VSS<634>"
$PN"BE26"4;
"VSS<635>"
$PN"BE10"4;
"VSS<636>"
$PN"BE8"4;
"VSS<637>"
$PN"BE6"4;
"VSS<638>"
$PN"BE4"4;
"VSS<639>"
$PN"BD71"4;
"VSS<640>"
$PN"BD63"4;
"VSS<641>"
$PN"BD27"4;
"VSS<642>"
$PN"BD21"4;
"VSS<643>"
$PN"BD15"4;
"VSS<644>"
$PN"BD11"4;
"VSS<645>"
$PN"BD5"4;
"VSS<646>"
$PN"BC82"4;
"VSS<647>"
$PN"BC80"4;
"VSS<648>"
$PN"BC78"4;
"VSS<649>"
$PN"BC76"4;
"VSS<650>"
$PN"BC74"4;
"VSS<651>"
$PN"BC72"4;
"VSS<652>"
$PN"BC70"4;
"VSS<653>"
$PN"BC16"4;
"VSS<654>"
$PN"BC12"4;
"VSS<655>"
$PN"BC8"4;
"VSS<656>"
$PN"BC4"4;
"VSS<657>"
$PN"BB83"4;
"VSS<658>"
$PN"BB81"4;
"VSS<659>"
$PN"BB79"4;
"VSS<660>"
$PN"BB77"4;
"VSS<661>"
$PN"BB75"4;
"VSS<662>"
$PN"BB73"4;
"VSS<663>"
$PN"BB69"4;
"VSS<664>"
$PN"BB63"4;
"VSS<665>"
$PN"BB23"4;
"VSS<666>"
$PN"BB19"4;
"VSS<667>"
$PN"BA84"4;
"VSS<668>"
$PN"BA80"4;
"VSS<669>"
$PN"BA74"4;
"VSS<670>"
$PN"BA68"4;
"VSS<671>"
$PN"BA62"4;
"VSS<672>"
$PN"BA12"4;
"VSS<673>"
$PN"BA6"4;
"VSS<674>"
$PN"BA2"4;
"VSS<675>"
$PN"AY81"4;
"VSS<676>"
$PN"AY79"4;
"VSS<677>"
$PN"AY63"4;
"VSS<678>"
$PN"AY25"4;
"VSS<679>"
$PN"AY23"4;
"VSS<680>"
$PN"AY21"4;
"VSS<681>"
$PN"AY17"4;
"VSS<682>"
$PN"AY15"4;
"VSS<683>"
$PN"AY5"4;
"VSS<684>"
$PN"AW84"4;
"VSS<685>"
$PN"AW82"4;
"VSS<686>"
$PN"AW78"4;
"VSS<687>"
$PN"AW74"4;
"VSS<688>"
$PN"AW72"4;
"VSS<689>"
$PN"AW70"4;
"VSS<690>"
$PN"AW68"4;
"VSS<691>"
$PN"AW66"4;
"VSS<692>"
$PN"AW62"4;
"VSS<693>"
$PN"AW10"4;
"VSS<694>"
$PN"AW2"3;
"VSS<695>"
$PN"AV83"3;
"VSS<696>"
$PN"AV75"3;
"VSS<697>"
$PN"AV67"3;
"VSS<698>"
$PN"AV65"3;
"VSS<699>"
$PN"AV63"3;
"VSS<700>"
$PN"AV25"3;
"VSS<701>"
$PN"AV23"3;
"VSS<702>"
$PN"AV19"3;
"VSS<703>"
$PN"AV13"3;
"VSS<704>"
$PN"AV11"3;
"VSS<705>"
$PN"AV7"3;
"VSS<706>"
$PN"AV3"3;
"VSS<707>"
$PN"AV1"3;
"VSS<708>"
$PN"AU86"3;
"VSS<709>"
$PN"AU84"3;
"VSS<710>"
$PN"AU80"3;
"VSS<711>"
$PN"AU78"3;
"VSS<712>"
$PN"AU76"3;
"VSS<713>"
$PN"AU74"3;
"VSS<714>"
$PN"AU68"3;
"VSS<715>"
$PN"AU64"3;
"VSS<716>"
$PN"AU62"3;
"VSS<717>"
$PN"AU28"3;
"VSS<718>"
$PN"AU26"3;
"VSS<719>"
$PN"AU6"3;
"VSS<720>"
$PN"AU2"3;
"VSS<721>"
$PN"AT85"3;
"VSS<722>"
$PN"AT83"3;
"VSS<723>"
$PN"AT77"3;
"VSS<724>"
$PN"AT73"3;
"VSS<725>"
$PN"AT69"3;
"VSS<726>"
$PN"AT63"3;
"VSS<727>"
$PN"AT61"3;
"VSS<728>"
$PN"AT27"3;
"VSS<729>"
$PN"AT21"3;
"VSS<730>"
$PN"AT17"3;
"VSS<731>"
$PN"AT15"3;
"VSS<732>"
$PN"P63"3;
"VSS<733>"
$PN"AC48"3;
"VSS<734>"
$PN"AR78"3;
"VSS<735>"
$PN"AR72"3;
"VSS<736>"
$PN"AR60"3;
"VSS<737>"
$PN"AR30"3;
"VSS<738>"
$PN"AR24"3;
"VSS<739>"
$PN"AR10"3;
"VSS<740>"
$PN"AP85"3;
"VSS<741>"
$PN"AP83"3;
"VSS<742>"
$PN"AP81"3;
"VSS<743>"
$PN"AP75"3;
"VSS<744>"
$PN"AP73"3;
"VSS<745>"
$PN"AP69"3;
"VSS<746>"
$PN"AP67"3;
"VSS<747>"
$PN"AP65"3;
"VSS<748>"
$PN"AP63"3;
"VSS<749>"
$PN"AP59"3;
"VSS<750>"
$PN"AP31"3;
"VSS<751>"
$PN"AP19"3;
"VSS<752>"
$PN"AP13"3;
"VSS<753>"
$PN"AP9"3;
"VSS<754>"
$PN"AP5"3;
"VSS<755>"
$PN"AN78"3;
"VSS<756>"
$PN"AN58"3;
"VSS<757>"
$PN"AN28"3;
"VSS<758>"
$PN"AN6"3;
"VSS<759>"
$PN"AN2"3;
"VSS<760>"
$PN"AM83"3;
"VSS<761>"
$PN"AM79"3;
"VSS<762>"
$PN"AM73"3;
"VSS<763>"
$PN"AM69"3;
"VSS<764>"
$PN"AM63"3;
"VSS<765>"
$PN"AM57"3;
"VSS<766>"
$PN"AM31"3;
"VSS<767>"
$PN"AC50"3;
"VSS<768>"
$PN"AM1"3;
"VSS<769>"
$PN"AL86"3;
"VSS<770>"
$PN"AL82"3;
"VSS<771>"
$PN"AL80"3;
"VSS<772>"
$PN"AL78"3;
"VSS<773>"
$PN"AL76"3;
%"GND"
"1","(-6100,475)","0","mstr_symbols","I3";
;
HDL_POWER"GND"
BODY_TYPE"PLUMBING"
CDS_LIB"mstr_symbols"
SIZE"1B"
VOLTAGE"0.0V";
"A\NAC"5;
%"GND"
"1","(-5775,500)","0","mstr_symbols","I4";
;
HDL_POWER"GND"
BODY_TYPE"PLUMBING"
CDS_LIB"mstr_symbols"
SIZE"1B"
VOLTAGE"0.0V";
"A\NAC"6;
%"GND"
"1","(-4250,500)","0","mstr_symbols","I6";
;
HDL_POWER"GND"
BODY_TYPE"PLUMBING"
CDS_LIB"mstr_symbols"
SIZE"1B"
VOLTAGE"0.0V";
"A\NAC"7;
%"GND"
"1","(-3950,500)","0","mstr_symbols","I9";
;
HDL_POWER"GND"
BODY_TYPE"PLUMBING"
SIZE"1B"
CDS_LIB"mstr_symbols"
VOLTAGE"0.0V";
"A\NAC"8;
END.
